FILE_TYPE = MACRO_DRAWING;
SET COLOR_WIRE YELLOW;
SET COLOR_PROP ORANGE;
SET COLOR_DOT WHITE;
SET COLOR_ARC YELLOW;
SET COLOR_BODY GREEN;
SET COLOR_NOTE PURPLE;
SET PROP_DISPLAY VALUE;
SET PAGE_NUMBER P21;
FORCEADD SHEET_A1..1
(2150 -800);
FORCEPROP 2 LAST CUSTOM_TXT_CDS <XR_PAGE_TITLE>
J 0
(-13420 10550);
DISPLAY 0.638298 (-13420 10550);
PAINT PINK (-13420 10550);
FORCEPROP 1 LAST CUSTOM_TXT_CDS <DOCNO>
J 0
(100 -415);
DISPLAY 0.978723 (100 -415);
FORCEPROP 1 LAST CUSTOM_TXT_CDS <CON_PAGE_NUM>
J 0
(-5 -750);
DISPLAY 0.978723 (-5 -750);
FORCEPROP 1 LAST CUSTOM_TXT_CDS <DATE>
J 0
(1450 -625);
DISPLAY 0.978723 (1450 -625);
FORCEPROP 1 LAST CUSTOM_TXT_CDS <TITLE>
J 1
(365 -170);
DISPLAY 0.978723 (365 -170);
FORCEPROP 1 LAST CUSTOM_TXT_CDS <DESIGNER>
J 0
(1450 -200);
DISPLAY 0.978723 (1450 -200);
FORCEPROP 1 LAST CUSTOM_TXT_CDS <CON_TOTAL_PAGES>
J 0
(305 -750);
DISPLAY 0.808511 (305 -750);
FORCEPROP 1 LAST CUSTOM_TXT_CDS <ASSY_PN>
J 0
(100 -625);
DISPLAY 0.978723 (100 -625);
FORCEPROP 1 LAST CUSTOM_TXT_CDS <DOCREV>
J 0
(1450 -425);
DISPLAY 0.978723 (1450 -425);
FORCEPROP 1 LAST COMMENT_BODY TRUE
J 0
(2160 -745);
DISPLAY 0.808511 (2160 -745);
DISPLAY INVISIBLE (2160 -745);
FORCEPROP 2 LAST PAGE_BORDER TRUE
J 0
(-13420 10550);
DISPLAY 0.638298 (-13420 10550);
PAINT PINK (-13420 10550);
DISPLAY INVISIBLE (-13420 10550);
FORCEPROP 1 LAST CDS_LMAN_SYM_OUTLINE -15850,11500,200,-200
J 0
(2150 -800);
DISPLAY 0.468085 (2150 -800);
PAINT GREEN (2150 -800);
DISPLAY INVISIBLE (2150 -800);
FORCEPROP 2 LAST CDS_LIB cls
J 0
(2150 -800);
DISPLAY INVISIBLE (2150 -800);
FORCEPROP 1 LAST TITLE SYS_BLOCK_DIAGRAM
J 0
(2150 -800);
PAINT MONO (2150 -800);
DISPLAY INVISIBLE (2150 -800);
FORCEPROP 2 LAST CDS_XR_PAGE_TITLE CR-3 : @TIMECARD_LIB.TIMECARD(SCH_1):PAGE3
J 0
(-13420 10550);
DISPLAY 0.638298 (-13420 10550);
PAINT PINK (-13420 10550);
DISPLAY INVISIBLE (-13420 10550);
FORCENOTE
SYS_BLOCK_DIAGRAM
(-7850 9450) 0;
DISPLAY LEFT (-7850 9450);
DISPLAY 6.148936 (-7850 9450);
FORCENOTE
$CDS_IMAGE|clipboard_6.jpg|11514|4660
(-5500 5800) 0;
DISPLAY LEFT (-5500 5800);
QUIT
